# T6G (Grand Teton) — schematic netlist excerpt (pin names and nets, part order shuffled) for the footprints in the layout excerpt that follows; sources: Cadence DE-HDL packaged netlist, KiCad conversion of 04192023_DAF0TMB3IC0_F0TG_MB_C_brd_V02_OCP.brd

PC6009  Q_CAP  1UF 25V 10% X6S  pkg C0402  page 270 : A = P1V2_AUX_VCC ; B = GND
PR198  Q_RES  5.6 1% CHIP  pkg 0402LF  page 212 : A = SW_PVDDCR_CPU0_P1_BOOT4 ; B = SW_PVDDCR_CPU0_P1_BOOT4_RC

(kicad_pcb
	(version 20260206)
	(generator "pcbnew")
	(generator_version "10.0")
	(general
		(thickness 1.6)
		(legacy_teardrops no)
	)
	(paper "A4")
	(title_block
		(title "04192023_DAF0TMB3IC0_F0TG_MB_C_brd_V02_OCP.brd")
		(comment 1 "Grand Teton / footprints 2530-2531 of 8354")
	)
	(layers
		(0 "F.Cu" signal "TOP")
		(4 "In1.Cu" signal "GND")
		(6 "In2.Cu" signal "IN1")
		(8 "In3.Cu" signal "GND1")
		(10 "In4.Cu" signal "IN2")
		(12 "In5.Cu" signal "GND2")
		(14 "In6.Cu" signal "IN3")
		(16 "In7.Cu" signal "GND3")
		(18 "In8.Cu" signal "VCC")
		(20 "In9.Cu" signal "VCC1")
		(22 "In10.Cu" signal "GND4")
		(24 "In11.Cu" signal "IN4")
		(26 "In12.Cu" signal "GND5")
		(28 "In13.Cu" signal "IN5")
		(30 "In14.Cu" signal "GND6")
		(32 "In15.Cu" signal "IN6")
		(34 "In16.Cu" signal "GND7")
		(2 "B.Cu" signal "BOTTOM")
		(9 "F.Adhes" user "F.Adhesive")
		(11 "B.Adhes" user "B.Adhesive")
		(13 "F.Paste" user "Package Geometry/Pastemask Top")
		(15 "B.Paste" user "Package Geometry/Pastemask Bottom")
		(5 "F.SilkS" user "Ref Des/Silkscreen Top")
		(7 "B.SilkS" user "Ref Des/Silkscreen Bottom")
		(1 "F.Mask" user "Board Geometry/Soldermask Top")
		(3 "B.Mask" user "Board Geometry/Soldermask Bottom")
		(17 "Dwgs.User" user "User.Drawings")
		(19 "Cmts.User" user "User.Comments")
		(21 "Eco1.User" user "User.Eco1")
		(23 "Eco2.User" user "User.Eco2")
		(25 "Edge.Cuts" user "Board Geometry/Outline")
		(27 "Margin" user)
		(31 "F.CrtYd" user "Package Geometry/Place Bound Top")
		(29 "B.CrtYd" user "Package Geometry/Place Bound Bottom")
		(35 "F.Fab" user "Ref Des/Assembly Top")
		(33 "B.Fab" user "Ref Des/Assembly Bottom")
	)
	(footprint ""
		(layer "F.Cu")
		(at 121.36247 -78.691486 180)
		(property "Reference" "PC6009"
			(at 0 0 180)
			(layer "F.SilkS")
			(hide yes)
			(effects
				(font
					(size 1.27 1.27)
				)
			)
		)
		(property "Value" ""
			(at 0 0 180)
			(layer "F.Fab")
			(effects
				(font
					(size 1.27 1.27)
				)
			)
		)
		(duplicate_pad_numbers_are_jumpers no)
		(fp_line
			(start 0.7874 0.4064)
			(end -0.7874 0.4064)
			(stroke
				(width 0.1524)
				(type default)
			)
			(layer "F.SilkS")
		)
		(fp_line
			(start 0.7874 -0.4064)
			(end 0.7874 0.4064)
			(stroke
				(width 0.1524)
				(type default)
			)
			(layer "F.SilkS")
		)
		(fp_line
			(start -0.7874 0.4064)
			(end -0.7874 -0.4064)
			(stroke
				(width 0.1524)
				(type default)
			)
			(layer "F.SilkS")
		)
		(fp_line
			(start -0.7874 -0.4064)
			(end 0.7874 -0.4064)
			(stroke
				(width 0.1524)
				(type default)
			)
			(layer "F.SilkS")
		)
		(fp_line
			(start 0.67945 0.3048)
			(end 0.120396 0.3048)
			(stroke
				(width 0.1)
				(type default)
			)
			(layer "F.Fab")
		)
		(fp_line
			(start 0.67945 -0.3048)
			(end 0.67945 0.3048)
			(stroke
				(width 0.1)
				(type default)
			)
			(layer "F.Fab")
		)
		(fp_line
			(start 0.12065 -0.2794)
			(end 0.12065 -0.3048)
			(stroke
				(width 0.1)
				(type default)
			)
			(layer "F.Fab")
		)
		(fp_line
			(start 0.12065 -0.3048)
			(end 0.67945 -0.3048)
			(stroke
				(width 0.1)
				(type default)
			)
			(layer "F.Fab")
		)
		(fp_line
			(start 0.120396 0.3048)
			(end 0.120396 0.2794)
			(stroke
				(width 0.1)
				(type default)
			)
			(layer "F.Fab")
		)
		(fp_line
			(start 0.120396 0.2794)
			(end -0.12065 0.2794)
			(stroke
				(width 0.1)
				(type default)
			)
			(layer "F.Fab")
		)
		(fp_line
			(start -0.12065 0.3048)
			(end -0.67945 0.3048)
			(stroke
				(width 0.1)
				(type default)
			)
			(layer "F.Fab")
		)
		(fp_line
			(start -0.12065 0.2794)
			(end -0.12065 0.3048)
			(stroke
				(width 0.1)
				(type default)
			)
			(layer "F.Fab")
		)
		(fp_line
			(start -0.12065 -0.2794)
			(end 0.12065 -0.2794)
			(stroke
				(width 0.1)
				(type default)
			)
			(layer "F.Fab")
		)
		(fp_line
			(start -0.12065 -0.305054)
			(end -0.12065 -0.2794)
			(stroke
				(width 0.1)
				(type default)
			)
			(layer "F.Fab")
		)
		(fp_line
			(start -0.67945 0.3048)
			(end -0.67945 -0.305054)
			(stroke
				(width 0.1)
				(type default)
			)
			(layer "F.Fab")
		)
		(fp_line
			(start -0.67945 -0.305054)
			(end -0.12065 -0.305054)
			(stroke
				(width 0.1)
				(type default)
			)
			(layer "F.Fab")
		)
		(pad "1" smd circle
			(at -0.40005 0 180)
			(size 0 0)
			(layers "F.Cu" "F.Mask" "F.Paste")
			(net "P1V2_AUX_VCC")
		)
		(pad "2" smd circle
			(at 0.40005 0 180)
			(size 0 0)
			(layers "F.Cu" "F.Mask" "F.Paste")
			(net "GND")
		)
	)
	(footprint ""
		(layer "F.Cu")
		(at 106.696764 -173.5201 -90)
		(property "Reference" "PR198"
			(at 0 0 270)
			(layer "F.SilkS")
			(hide yes)
			(effects
				(font
					(size 1.27 1.27)
				)
			)
		)
		(property "Value" ""
			(at 0 0 270)
			(layer "F.Fab")
			(effects
				(font
					(size 1.27 1.27)
				)
			)
		)
		(duplicate_pad_numbers_are_jumpers no)
		(fp_line
			(start -0.7874 0.4064)
			(end -0.7874 -0.4064)
			(stroke
				(width 0.1524)
				(type default)
			)
			(layer "F.SilkS")
		)
		(fp_line
			(start 0.7874 0.4064)
			(end -0.7874 0.4064)
			(stroke
				(width 0.1524)
				(type default)
			)
			(layer "F.SilkS")
		)
		(fp_line
			(start -0.7874 -0.4064)
			(end 0.7874 -0.4064)
			(stroke
				(width 0.1524)
				(type default)
			)
			(layer "F.SilkS")
		)
		(fp_line
			(start 0.7874 -0.4064)
			(end 0.7874 0.4064)
			(stroke
				(width 0.1524)
				(type default)
			)
			(layer "F.SilkS")
		)
		(fp_line
			(start -0.67945 0.3048)
			(end -0.67945 -0.305054)
			(stroke
				(width 0.1)
				(type default)
			)
			(layer "F.Fab")
		)
		(fp_line
			(start -0.12065 0.3048)
			(end -0.67945 0.3048)
			(stroke
				(width 0.1)
				(type default)
			)
			(layer "F.Fab")
		)
		(fp_line
			(start 0.120396 0.3048)
			(end 0.120396 0.2794)
			(stroke
				(width 0.1)
				(type default)
			)
			(layer "F.Fab")
		)
		(fp_line
			(start 0.67945 0.3048)
			(end 0.120396 0.3048)
			(stroke
				(width 0.1)
				(type default)
			)
			(layer "F.Fab")
		)
		(fp_line
			(start -0.12065 0.2794)
			(end -0.12065 0.3048)
			(stroke
				(width 0.1)
				(type default)
			)
			(layer "F.Fab")
		)
		(fp_line
			(start 0.120396 0.2794)
			(end -0.12065 0.2794)
			(stroke
				(width 0.1)
				(type default)
			)
			(layer "F.Fab")
		)
		(fp_line
			(start -0.12065 -0.2794)
			(end 0.12065 -0.2794)
			(stroke
				(width 0.1)
				(type default)
			)
			(layer "F.Fab")
		)
		(fp_line
			(start 0.12065 -0.2794)
			(end 0.12065 -0.3048)
			(stroke
				(width 0.1)
				(type default)
			)
			(layer "F.Fab")
		)
		(fp_line
			(start 0.12065 -0.3048)
			(end 0.67945 -0.3048)
			(stroke
				(width 0.1)
				(type default)
			)
			(layer "F.Fab")
		)
		(fp_line
			(start 0.67945 -0.3048)
			(end 0.67945 0.3048)
			(stroke
				(width 0.1)
				(type default)
			)
			(layer "F.Fab")
		)
		(fp_line
			(start -0.67945 -0.305054)
			(end -0.12065 -0.305054)
			(stroke
				(width 0.1)
				(type default)
			)
			(layer "F.Fab")
		)
		(fp_line
			(start -0.12065 -0.305054)
			(end -0.12065 -0.2794)
			(stroke
				(width 0.1)
				(type default)
			)
			(layer "F.Fab")
		)
		(pad "1" smd circle
			(at -0.40005 0 270)
			(size 0 0)
			(layers "F.Cu" "F.Mask" "F.Paste")
			(net "SW_PVDDCR_CPU0_P1_BOOT4")
		)
		(pad "2" smd circle
			(at 0.40005 0 270)
			(size 0 0)
			(layers "F.Cu" "F.Mask" "F.Paste")
			(net "SW_PVDDCR_CPU0_P1_BOOT4_RC")
		)
	)
)
